# S9S_MB_2U (Grand Teton) — schematic netlist excerpt (pin names and nets, part order shuffled) for the footprints in the layout excerpt that follows; sources: Cadence DE-HDL packaged netlist, KiCad conversion of 03242023_DA0F0TMBIJ0_F0T_Motherboard_J_brd_V01_OCP.brd

PR303  Q_RES  0 5% CHIP  pkg 0402LF  page 284 : A = P12V_AUX ; B = PVCCIN_CPU1_VIN_CSNIN
R5238  Q_RES  3.9K 5% EMPTY  pkg 0402LF  page 152 : A = PD_U5201_EQ ; B = GND
C457  Q_CAP  47UF 4V 20% X6S  pkg C0805  page 78 : A = PVCCFA_EHV_FIVRA_CPU1 ; B = GND

(kicad_pcb
	(version 20260206)
	(generator "pcbnew")
	(generator_version "10.0")
	(general
		(thickness 1.6)
		(legacy_teardrops no)
	)
	(paper "A4")
	(title_block
		(title "03242023_DA0F0TMBIJ0_F0T_Motherboard_J_brd_V01_OCP.brd")
		(comment 1 "Grand Teton / footprints 5314-5316 of 6105")
	)
	(layers
		(0 "F.Cu" signal "TOP")
		(4 "In1.Cu" signal "GND")
		(6 "In2.Cu" signal "IN1")
		(8 "In3.Cu" signal "GND1")
		(10 "In4.Cu" signal "IN2")
		(12 "In5.Cu" signal "GND2")
		(14 "In6.Cu" signal "IN3")
		(16 "In7.Cu" signal "GND3")
		(18 "In8.Cu" signal "VCC")
		(20 "In9.Cu" signal "VCC1")
		(22 "In10.Cu" signal "GND4")
		(24 "In11.Cu" signal "IN4")
		(26 "In12.Cu" signal "GND5")
		(28 "In13.Cu" signal "IN5")
		(30 "In14.Cu" signal "GND6")
		(32 "In15.Cu" signal "IN6")
		(34 "In16.Cu" signal "GND7")
		(2 "B.Cu" signal "BOTTOM")
		(9 "F.Adhes" user "F.Adhesive")
		(11 "B.Adhes" user "B.Adhesive")
		(13 "F.Paste" user "Package Geometry/Pastemask Top")
		(15 "B.Paste" user "Package Geometry/Pastemask Bottom")
		(5 "F.SilkS" user "Ref Des/Silkscreen Top")
		(7 "B.SilkS" user "Ref Des/Silkscreen Bottom")
		(1 "F.Mask" user "Board Geometry/Soldermask Top")
		(3 "B.Mask" user "Board Geometry/Soldermask Bottom")
		(17 "Dwgs.User" user "User.Drawings")
		(19 "Cmts.User" user "User.Comments")
		(21 "Eco1.User" user "User.Eco1")
		(23 "Eco2.User" user "User.Eco2")
		(25 "Edge.Cuts" user "Board Geometry/Outline")
		(27 "Margin" user)
		(31 "F.CrtYd" user "Package Geometry/Place Bound Top")
		(29 "B.CrtYd" user "Package Geometry/Place Bound Bottom")
		(35 "F.Fab" user "Ref Des/Assembly Top")
		(33 "B.Fab" user "Ref Des/Assembly Bottom")
	)
	(footprint ""
		(layer "B.Cu")
		(at 113.78438 -361.764326)
		(property "Reference" "PR303"
			(at 0 0 0)
			(layer "B.SilkS")
			(hide yes)
			(effects
				(font
					(size 1.27 1.27)
				)
				(justify mirror)
			)
		)
		(property "Value" ""
			(at 0 0 0)
			(layer "B.Fab")
			(effects
				(font
					(size 1.27 1.27)
				)
				(justify mirror)
			)
		)
		(duplicate_pad_numbers_are_jumpers no)
		(fp_line
			(start -0.7874 -0.4064)
			(end -0.7874 0.4064)
			(stroke
				(width 0.1524)
				(type default)
			)
			(layer "B.SilkS")
		)
		(fp_line
			(start -0.7874 0.4064)
			(end 0.7874 0.4064)
			(stroke
				(width 0.1524)
				(type default)
			)
			(layer "B.SilkS")
		)
		(fp_line
			(start 0.7874 -0.4064)
			(end -0.7874 -0.4064)
			(stroke
				(width 0.1524)
				(type default)
			)
			(layer "B.SilkS")
		)
		(fp_line
			(start 0.7874 0.4064)
			(end 0.7874 -0.4064)
			(stroke
				(width 0.1524)
				(type default)
			)
			(layer "B.SilkS")
		)
		(fp_line
			(start -0.67945 -0.3048)
			(end -0.67945 0.3048)
			(stroke
				(width 0.1)
				(type default)
			)
			(layer "B.Fab")
		)
		(fp_line
			(start -0.67945 0.3048)
			(end -0.120396 0.3048)
			(stroke
				(width 0.1)
				(type default)
			)
			(layer "B.Fab")
		)
		(fp_line
			(start -0.12065 -0.3048)
			(end -0.67945 -0.3048)
			(stroke
				(width 0.1)
				(type default)
			)
			(layer "B.Fab")
		)
		(fp_line
			(start -0.12065 -0.2794)
			(end -0.12065 -0.3048)
			(stroke
				(width 0.1)
				(type default)
			)
			(layer "B.Fab")
		)
		(fp_line
			(start -0.120396 0.2794)
			(end 0.12065 0.2794)
			(stroke
				(width 0.1)
				(type default)
			)
			(layer "B.Fab")
		)
		(fp_line
			(start -0.120396 0.3048)
			(end -0.120396 0.2794)
			(stroke
				(width 0.1)
				(type default)
			)
			(layer "B.Fab")
		)
		(fp_line
			(start 0.12065 -0.305054)
			(end 0.12065 -0.2794)
			(stroke
				(width 0.1)
				(type default)
			)
			(layer "B.Fab")
		)
		(fp_line
			(start 0.12065 -0.2794)
			(end -0.12065 -0.2794)
			(stroke
				(width 0.1)
				(type default)
			)
			(layer "B.Fab")
		)
		(fp_line
			(start 0.12065 0.2794)
			(end 0.12065 0.3048)
			(stroke
				(width 0.1)
				(type default)
			)
			(layer "B.Fab")
		)
		(fp_line
			(start 0.12065 0.3048)
			(end 0.67945 0.3048)
			(stroke
				(width 0.1)
				(type default)
			)
			(layer "B.Fab")
		)
		(fp_line
			(start 0.67945 -0.305054)
			(end 0.12065 -0.305054)
			(stroke
				(width 0.1)
				(type default)
			)
			(layer "B.Fab")
		)
		(fp_line
			(start 0.67945 0.3048)
			(end 0.67945 -0.305054)
			(stroke
				(width 0.1)
				(type default)
			)
			(layer "B.Fab")
		)
		(pad "1" smd circle
			(at 0.40005 0 180)
			(size 0 0)
			(layers "B.Cu" "B.Mask" "B.Paste")
			(net "P12V_AUX")
		)
		(pad "2" smd circle
			(at -0.40005 0 180)
			(size 0 0)
			(layers "B.Cu" "B.Mask" "B.Paste")
			(net "PVCCIN_CPU1_VIN_CSNIN")
		)
	)
	(footprint ""
		(layer "B.Cu")
		(at 8.19277 -113.161826)
		(property "Reference" "R5238"
			(at 0 0 0)
			(layer "B.SilkS")
			(hide yes)
			(effects
				(font
					(size 1.27 1.27)
				)
				(justify mirror)
			)
		)
		(property "Value" ""
			(at 0 0 0)
			(layer "B.Fab")
			(effects
				(font
					(size 1.27 1.27)
				)
				(justify mirror)
			)
		)
		(duplicate_pad_numbers_are_jumpers no)
		(fp_line
			(start -0.7874 -0.4064)
			(end -0.7874 0.4064)
			(stroke
				(width 0.1524)
				(type default)
			)
			(layer "B.SilkS")
		)
		(fp_line
			(start -0.7874 0.4064)
			(end 0.7874 0.4064)
			(stroke
				(width 0.1524)
				(type default)
			)
			(layer "B.SilkS")
		)
		(fp_line
			(start 0.7874 -0.4064)
			(end -0.7874 -0.4064)
			(stroke
				(width 0.1524)
				(type default)
			)
			(layer "B.SilkS")
		)
		(fp_line
			(start 0.7874 0.4064)
			(end 0.7874 -0.4064)
			(stroke
				(width 0.1524)
				(type default)
			)
			(layer "B.SilkS")
		)
		(fp_line
			(start -0.67945 -0.3048)
			(end -0.67945 0.3048)
			(stroke
				(width 0.1)
				(type default)
			)
			(layer "B.Fab")
		)
		(fp_line
			(start -0.67945 0.3048)
			(end -0.120396 0.3048)
			(stroke
				(width 0.1)
				(type default)
			)
			(layer "B.Fab")
		)
		(fp_line
			(start -0.12065 -0.3048)
			(end -0.67945 -0.3048)
			(stroke
				(width 0.1)
				(type default)
			)
			(layer "B.Fab")
		)
		(fp_line
			(start -0.12065 -0.2794)
			(end -0.12065 -0.3048)
			(stroke
				(width 0.1)
				(type default)
			)
			(layer "B.Fab")
		)
		(fp_line
			(start -0.120396 0.2794)
			(end 0.12065 0.2794)
			(stroke
				(width 0.1)
				(type default)
			)
			(layer "B.Fab")
		)
		(fp_line
			(start -0.120396 0.3048)
			(end -0.120396 0.2794)
			(stroke
				(width 0.1)
				(type default)
			)
			(layer "B.Fab")
		)
		(fp_line
			(start 0.12065 -0.305054)
			(end 0.12065 -0.2794)
			(stroke
				(width 0.1)
				(type default)
			)
			(layer "B.Fab")
		)
		(fp_line
			(start 0.12065 -0.2794)
			(end -0.12065 -0.2794)
			(stroke
				(width 0.1)
				(type default)
			)
			(layer "B.Fab")
		)
		(fp_line
			(start 0.12065 0.2794)
			(end 0.12065 0.3048)
			(stroke
				(width 0.1)
				(type default)
			)
			(layer "B.Fab")
		)
		(fp_line
			(start 0.12065 0.3048)
			(end 0.67945 0.3048)
			(stroke
				(width 0.1)
				(type default)
			)
			(layer "B.Fab")
		)
		(fp_line
			(start 0.67945 -0.305054)
			(end 0.12065 -0.305054)
			(stroke
				(width 0.1)
				(type default)
			)
			(layer "B.Fab")
		)
		(fp_line
			(start 0.67945 0.3048)
			(end 0.67945 -0.305054)
			(stroke
				(width 0.1)
				(type default)
			)
			(layer "B.Fab")
		)
		(pad "1" smd circle
			(at 0.40005 0 180)
			(size 0 0)
			(layers "B.Cu" "B.Mask" "B.Paste")
			(net "PD_U5201_EQ")
		)
		(pad "2" smd circle
			(at -0.40005 0 180)
			(size 0 0)
			(layers "B.Cu" "B.Mask" "B.Paste")
			(net "GND")
		)
	)
	(footprint ""
		(layer "B.Cu")
		(at 107.457494 -259.53212 90)
		(property "Reference" "C457"
			(at 0 0 90)
			(layer "B.SilkS")
			(hide yes)
			(effects
				(font
					(size 1.27 1.27)
				)
				(justify mirror)
			)
		)
		(property "Value" ""
			(at 0 0 90)
			(layer "B.Fab")
			(effects
				(font
					(size 1.27 1.27)
				)
				(justify mirror)
			)
		)
		(duplicate_pad_numbers_are_jumpers no)
		(fp_line
			(start 1.524 -0.762)
			(end -1.524 -0.762)
			(stroke
				(width 0.1524)
				(type default)
			)
			(layer "B.SilkS")
		)
		(fp_line
			(start -1.524 -0.762)
			(end -1.524 0.762)
			(stroke
				(width 0.1524)
				(type default)
			)
			(layer "B.SilkS")
		)
		(fp_line
			(start 1.524 0.762)
			(end 1.524 -0.762)
			(stroke
				(width 0.1524)
				(type default)
			)
			(layer "B.SilkS")
		)
		(fp_line
			(start -1.524 0.762)
			(end 1.524 0.762)
			(stroke
				(width 0.1524)
				(type default)
			)
			(layer "B.SilkS")
		)
		(fp_line
			(start 1.1049 -0.724916)
			(end 1.1049 0.724916)
			(stroke
				(width 0.1)
				(type default)
			)
			(layer "B.Fab")
		)
		(fp_line
			(start -1.1049 -0.724916)
			(end 1.1049 -0.724916)
			(stroke
				(width 0.1)
				(type default)
			)
			(layer "B.Fab")
		)
		(fp_line
			(start 1.1049 0.724916)
			(end -1.1049 0.724916)
			(stroke
				(width 0.1)
				(type default)
			)
			(layer "B.Fab")
		)
		(fp_line
			(start -1.1049 0.724916)
			(end -1.1049 -0.724916)
			(stroke
				(width 0.1)
				(type default)
			)
			(layer "B.Fab")
		)
		(pad "1" smd rect
			(at 0.889 0 90)
			(size 1.016 1.27)
			(layers "B.Cu" "B.Mask" "B.Paste")
			(net "PVCCFA_EHV_FIVRA_CPU1")
		)
		(pad "2" smd rect
			(at -0.889 0 90)
			(size 1.016 1.27)
			(layers "B.Cu" "B.Mask" "B.Paste")
			(net "GND")
		)
	)
)
